# S9S_MB_2U (Grand Teton) — schematic netlist excerpt (pin names and nets, part order shuffled) for the footprints in the layout excerpt that follows; sources: Cadence DE-HDL packaged netlist, KiCad conversion of 03242023_DA0F0TMBIJ0_F0T_Motherboard_J_brd_V01_OCP.brd

J19  SCONN288_ADR50017P130CC  SCONN288_ADR50017-P130CC IO  pkg DDR288S_1-1VXB  page 100
  VIN_BULK0  = P12V_S3_AUX_CPU1_NVDIMM
  RFU0  = TP_CHB_CPU1_DIMM1_FRU_0
  VIN_MGMT  = P3V3_AUX
  HSCL  = I3C_SPD_DDRABCD_CPU1_LVC1_SCL_2
  HSDA  = I3C_SPD_DDRABCD_CPU1_LVC1_SDA
  VSS0  = GND
  DQ0_A  = M_B_CPU1_SA_DQ<0>
  VSS1  = GND
  DQ1_A  = M_B_CPU1_SA_DQ<1>
  VSS2  = GND
  DQS0_A_T  = M_B_CPU1_SA_DQS_DP<0>
  DQS0_A_C  = M_B_CPU1_SA_DQS_DN<0>
  VSS3  = GND
  DQ4_A  = M_B_CPU1_SA_DQ<4>
  VSS4  = GND
  DQ5_A  = M_B_CPU1_SA_DQ<5>
  VSS5  = GND
  DQ8_A  = M_B_CPU1_SA_DQ<8>
  VSS6  = GND
  DQ9_A  = M_B_CPU1_SA_DQ<9>
  VSS7  = GND
  DQS1_A_T  = M_B_CPU1_SA_DQS_DP<1>
  DQS1_A_C  = M_B_CPU1_SA_DQS_DN<1>
  VSS8  = GND
  DQ12_A  = M_B_CPU1_SA_DQ<12>
  VSS9  = GND
  DQ13_A  = M_B_CPU1_SA_DQ<13>
  VSS10  = GND
  DQ16_A  = M_B_CPU1_SA_DQ<16>
  VSS11  = GND
  DQ17_A  = M_B_CPU1_SA_DQ<17>
  VSS12  = GND
  DQS2_A_T  = M_B_CPU1_SA_DQS_DP<2>
  DQS2_A_C  = M_B_CPU1_SA_DQS_DN<2>
  VSS13  = GND
  DQ20_A  = M_B_CPU1_SA_DQ<20>
  VSS14  = GND
  DQ21_A  = M_B_CPU1_SA_DQ<21>
  VSS15  = GND
  DQ24_A  = M_B_CPU1_SA_DQ<24>
  VSS16  = GND
  DQ25_A  = M_B_CPU1_SA_DQ<25>
  VSS17  = GND
  DQS3_A_T  = M_B_CPU1_SA_DQS_DP<3>
  DQS3_A_C  = M_B_CPU1_SA_DQS_DN<3>
  VSS18  = GND
  DQ28_A  = M_B_CPU1_SA_DQ<28>
  VSS19  = GND
  DQ29_A  = M_B_CPU1_SA_DQ<29>
  VSS20  = GND
  CB0_A  = M_B_CPU1_SA_CB<0>
  VSS21  = GND
  CB1_A  = M_B_CPU1_SA_CB<1>
  VSS22  = GND
  DQS4_A_T  = M_B_CPU1_SA_DQS_DP<4>
  DQS4_A_C  = M_B_CPU1_SA_DQS_DN<4>
  VSS23  = GND
  CB4_A  = M_B_CPU1_SA_CB<4>
  VSS24  = GND
  CB5_A  = M_B_CPU1_SA_CB<5>
  VSS25  = GND
  ALERT_N  = M_B_CPU1_ALERT_N
  VSS26  = GND
  CS0_A_N  = M_B_CPU1_SA_CS_N<0>
  VSS27  = GND
  CA0_A  = M_B_CPU1_SA_CA<0>
  VSS28  = GND
  CA2_A  = M_B_CPU1_SA_CA<2>
  VSS29  = GND
  CA4_A  = M_B_CPU1_SA_CA<4>
  VSS30  = GND
  CA6_A  = M_B_CPU1_SA_CA<6>
  VSS31  = GND
  PAR_A  = M_B_CPU1_SA_PAR
  VSS32  = GND
  CA0_B  = M_B_CPU1_SB_CA<0>
  VSS33  = GND
  CA2_B  = M_B_CPU1_SB_CA<2>
  VSS34  = GND
  CA4_B  = M_B_CPU1_SB_CA<4>
  VSS35  = GND
  CA6_B  = M_B_CPU1_SB_CA<6>
  VSS36  = GND
  CS0_B_N  = M_B_CPU1_SB_CS_N<0>
  VSS37  = GND
  \lbd||rsp_a_n\  = M_B_CPU1_SA_RSP<0>
  \lbs||rsp_b_n\  = M_B_CPU1_SB_RSP<0>
  VSS38  = GND
  CB4_B  = M_B_CPU1_SB_CB<4>
  VSS39  = GND
  CB5_B  = M_B_CPU1_SB_CB<5>
  VSS40  = GND
  \dqs9_b_t||tdqs9_b_t||dbi4_b_n\  = M_B_CPU1_SB_DQS_DP<9>
  \dqs9_b_c||tdqs9_b_c\  = M_B_CPU1_SB_DQS_DN<9>
  VSS41  = GND
  CB0_B  = M_B_CPU1_SB_CB<0>
  VSS42  = GND
  CB1_B  = M_B_CPU1_SB_CB<1>
  VSS43  = GND
  DQ0_B  = M_B_CPU1_SB_DQ<0>
  VSS44  = GND
  DQ1_B  = M_B_CPU1_SB_DQ<1>
  VSS45  = GND
  DQS0_B_T  = M_B_CPU1_SB_DQS_DP<0>
  DQS0_B_C  = M_B_CPU1_SB_DQS_DN<0>
  VSS46  = GND
  DQ4_B  = M_B_CPU1_SB_DQ<4>
  VSS47  = GND
  DQ5_B  = M_B_CPU1_SB_DQ<5>
  VSS48  = GND
  DQ8_B  = M_B_CPU1_SB_DQ<8>
  VSS49  = GND
  DQ9_B  = M_B_CPU1_SB_DQ<9>
  VSS50  = GND
  DQS1_B_T  = M_B_CPU1_SB_DQS_DP<1>
  DQS1_B_C  = M_B_CPU1_SB_DQS_DN<1>
  VSS51  = GND
  DQ12_B  = M_B_CPU1_SB_DQ<12>
  VSS52  = GND
  DQ13_B  = M_B_CPU1_SB_DQ<13>
  VSS53  = GND
  DQ16_B  = M_B_CPU1_SB_DQ<16>
  VSS54  = GND
  DQ17_B  = M_B_CPU1_SB_DQ<17>
  VSS55  = GND
  DQS2_B_T  = M_B_CPU1_SB_DQS_DP<2>
  DQS2_B_C  = M_B_CPU1_SB_DQS_DN<2>
  VSS56  = GND
  DQ20_B  = M_B_CPU1_SB_DQ<20>
  VSS57  = GND
  DQ21_B  = M_B_CPU1_SB_DQ<21>
  VSS58  = GND
  DQ24_B  = M_B_CPU1_SB_DQ<24>
  VSS59  = GND
  DQ25_B  = M_B_CPU1_SB_DQ<25>
  VSS60  = GND
  DQS3_B_T  = M_B_CPU1_SB_DQS_DP<3>
  DQS3_B_C  = M_B_CPU1_SB_DQS_DN<3>
  VSS61  = GND
  DQ28_B  = M_B_CPU1_SB_DQ<28>
  VSS62  = GND
  DQ29_B  = M_B_CPU1_SB_DQ<29>
  VSS63  = GND
  RFU1  = TP_CHB_CPU1_DIMM1_FRU_1
  VIN_BULK1  = P12V_S3_AUX_CPU1_NVDIMM
  VIN_BULK2  = P12V_S3_AUX_CPU1_NVDIMM
  \pwr_good||fail_n\  = PWRGD_CHB_CPU1_DIMM1
  HSA  = PD_CHB_CPU1_DIMM1_SAA
  RFU2  = TP_CHB_CPU1_DIMM1_FRU_2
  RFU3  = TP_CHB_CPU1_DIMM1_FRU_3
  VSS64  = GND
  DQ2_A  = M_B_CPU1_SA_DQ<2>
  VSS65  = GND
  DQ3_A  = M_B_CPU1_SA_DQ<3>
  VSS66  = GND
  \dqs5_a_c||tdqs5_a_c||dqs5_a_t||tdqs5_a_t\  = M_B_CPU1_SA_DQS_DN<5>
  \dqs5_a_t||tdqs5_a_t\  = M_B_CPU1_SA_DQS_DP<5>
  VSS67  = GND
  DQ6_A  = M_B_CPU1_SA_DQ<6>
  VSS68  = GND
  DQ7_A  = M_B_CPU1_SA_DQ<7>
  VSS69  = GND
  DQ10_A  = M_B_CPU1_SA_DQ<10>
  VSS70  = GND
  DQ11_A  = M_B_CPU1_SA_DQ<11>
  VSS71  = GND
  \dqs6_a_c||tdqs6_a_c||dqs6_a_t||tdqs6_a_t\  = M_B_CPU1_SA_DQS_DN<6>
  \dqs6_a_t||tdqs6_a_t\  = M_B_CPU1_SA_DQS_DP<6>
  VSS72  = GND
  DQ14_A  = M_B_CPU1_SA_DQ<14>
  VSS73  = GND
  DQ15_A  = M_B_CPU1_SA_DQ<15>
  VSS74  = GND
  DQ18_A  = M_B_CPU1_SA_DQ<18>
  VSS75  = GND
  DQ19_A  = M_B_CPU1_SA_DQ<19>
  VSS76  = GND
  \dqs7_a_c||tdqs7_a_c\  = M_B_CPU1_SA_DQS_DN<7>
  \dqs7_a_t||tdqs7_a_t\  = M_B_CPU1_SA_DQS_DP<7>
  VSS77  = GND
  DQ22_A  = M_B_CPU1_SA_DQ<22>
  VSS78  = GND
  DQ23_A  = M_B_CPU1_SA_DQ<23>
  VSS79  = GND
  DQ26_A  = M_B_CPU1_SA_DQ<26>
  VSS80  = GND
  DQ27_A  = M_B_CPU1_SA_DQ<27>
  VSS81  = GND
  \dqs8_a_c||tdqs8_a_c\  = M_B_CPU1_SA_DQS_DN<8>
  \dqs8_a_t||tdqs8_a_t\  = M_B_CPU1_SA_DQS_DP<8>
  VSS82  = GND
  DQ30_A  = M_B_CPU1_SA_DQ<30>
  VSS83  = GND
  DQ31_A  = M_B_CPU1_SA_DQ<31>
  VSS84  = GND
  CB2_A  = M_B_CPU1_SA_CB<2>
  VSS85  = GND
  CB3_A  = M_B_CPU1_SA_CB<3>
  VSS86  = GND
  \dqs9_a_c||tdqs9_a_c\  = M_B_CPU1_SA_DQS_DN<9>
  \dqs9_a_t||tdqs9_a_t\  = M_B_CPU1_SA_DQS_DP<9>
  VSS87  = GND
  CB6_A  = M_B_CPU1_SA_CB<6>
  VSS88  = GND
  CB7_A  = M_B_CPU1_SA_CB<7>
  VSS89  = GND
  RESET_N  = RST_M_AB_CPU1_FPGA_N
  VSS90  = GND
  CS1_A_N  = M_B_CPU1_SA_CS_N<1>
  VSS91  = GND
  CA1_A  = M_B_CPU1_SA_CA<1>
  VSS92  = GND
  CA3_A  = M_B_CPU1_SA_CA<3>
  VSS93  = GND
  CA5_A  = M_B_CPU1_SA_CA<5>
  VSS94  = GND
  CK_T  = M_B_CPU1_CLK_DP<0>
  CK_C  = M_B_CPU1_CLK_DN<0>
  VSS95  = GND
  RFU4  = TP_CHB_CPU1_DIMM1_FRU_4
  CA1_B  = M_B_CPU1_SB_CA<1>
  VSS96  = GND
  CA3_B  = M_B_CPU1_SB_CA<3>
  VSS97  = GND
  CA5_B  = M_B_CPU1_SB_CA<5>
  VSS98  = GND
  PAR_B  = M_B_CPU1_SB_PAR
  VSS99  = GND
  CS1_B_N  = M_B_CPU1_SB_CS_N<1>
  VSS100  = GND
  RFU5  = TP_CHB_CPU1_DIMM1_FRU_5
  RFU6  = TP_CHB_CPU1_DIMM1_FRU_6
  VSS101  = GND
  CB6_B  = M_B_CPU1_SB_CB<6>
  VSS102  = GND
  CB7_B  = M_B_CPU1_SB_CB<7>
  VSS103  = GND
  DQS4_B_C  = M_B_CPU1_SB_DQS_DN<4>
  DQS4_B_T  = M_B_CPU1_SB_DQS_DP<4>
  VSS104  = GND
  CB2_B  = M_B_CPU1_SB_CB<2>
  VSS105  = GND
  CB3_B  = M_B_CPU1_SB_CB<3>
  VSS106  = GND
  DQ2_B  = M_B_CPU1_SB_DQ<2>
  VSS107  = GND
  DQ3_B  = M_B_CPU1_SB_DQ<3>
  VSS108  = GND
  \dqs5_b_c||tdqs5_b_c\  = M_B_CPU1_SB_DQS_DN<5>
  \dqs5_b_t||tdqs5_b_t\  = M_B_CPU1_SB_DQS_DP<5>
  VSS109  = GND
  DQ6_B  = M_B_CPU1_SB_DQ<6>
  VSS110  = GND
  DQ7_B  = M_B_CPU1_SB_DQ<7>
  VSS111  = GND
  DQ10_B  = M_B_CPU1_SB_DQ<10>
  VSS112  = GND
  DQ11_B  = M_B_CPU1_SB_DQ<11>
  VSS113  = GND
  \dqs6_b_c||tdqs6_b_c\  = M_B_CPU1_SB_DQS_DN<6>
  \dqs6_b_t||tdqs6_b_t\  = M_B_CPU1_SB_DQS_DP<6>
  VSS114  = GND
  DQ14_B  = M_B_CPU1_SB_DQ<14>
  VSS115  = GND
  DQ15_B  = M_B_CPU1_SB_DQ<15>
  VSS116  = GND
  DQ18_B  = M_B_CPU1_SB_DQ<18>
  VSS117  = GND
  DQ19_B  = M_B_CPU1_SB_DQ<19>
  VSS118  = GND
  \dqs7_b_c||tdqs7_b_c\  = M_B_CPU1_SB_DQS_DN<7>
  \dqs7_b_t||tdqs7_b_t\  = M_B_CPU1_SB_DQS_DP<7>
  VSS119  = GND
  DQ22_B  = M_B_CPU1_SB_DQ<22>
  VSS120  = GND
  DQ23_B  = M_B_CPU1_SB_DQ<23>
  VSS121  = GND
  DQ26_B  = M_B_CPU1_SB_DQ<26>
  VSS122  = GND
  DQ27_B  = M_B_CPU1_SB_DQ<27>
  VSS123  = GND
  \dqs8_b_c||tdqs8_b_c\  = M_B_CPU1_SB_DQS_DN<8>
  \dqs8_b_t||tdqs8_b_t\  = M_B_CPU1_SB_DQS_DP<8>
  VSS124  = GND
  DQ30_B  = M_B_CPU1_SB_DQ<30>
  VSS125  = GND
  DQ31_B  = M_B_CPU1_SB_DQ<31>
  VSS126  = GND
  G1  = GND
  G2  = GND
  G3  = GND

(kicad_pcb
	(version 20260206)
	(generator "pcbnew")
	(generator_version "10.0")
	(general
		(thickness 1.6)
		(legacy_teardrops no)
	)
	(paper "A4")
	(title_block
		(title "03242023_DA0F0TMBIJ0_F0T_Motherboard_J_brd_V01_OCP.brd")
		(comment 1 "Grand Teton / footprint 2188 of 6105 (J19), pads 183-228 of 291")
	)
	(layers
		(0 "F.Cu" signal "TOP")
		(4 "In1.Cu" signal "GND")
		(6 "In2.Cu" signal "IN1")
		(8 "In3.Cu" signal "GND1")
		(10 "In4.Cu" signal "IN2")
		(12 "In5.Cu" signal "GND2")
		(14 "In6.Cu" signal "IN3")
		(16 "In7.Cu" signal "GND3")
		(18 "In8.Cu" signal "VCC")
		(20 "In9.Cu" signal "VCC1")
		(22 "In10.Cu" signal "GND4")
		(24 "In11.Cu" signal "IN4")
		(26 "In12.Cu" signal "GND5")
		(28 "In13.Cu" signal "IN5")
		(30 "In14.Cu" signal "GND6")
		(32 "In15.Cu" signal "IN6")
		(34 "In16.Cu" signal "GND7")
		(2 "B.Cu" signal "BOTTOM")
		(9 "F.Adhes" user "F.Adhesive")
		(11 "B.Adhes" user "B.Adhesive")
		(13 "F.Paste" user "Package Geometry/Pastemask Top")
		(15 "B.Paste" user "Package Geometry/Pastemask Bottom")
		(5 "F.SilkS" user "Ref Des/Silkscreen Top")
		(7 "B.SilkS" user "Ref Des/Silkscreen Bottom")
		(1 "F.Mask" user "Board Geometry/Soldermask Top")
		(3 "B.Mask" user "Board Geometry/Soldermask Bottom")
		(17 "Dwgs.User" user "User.Drawings")
		(19 "Cmts.User" user "User.Comments")
		(21 "Eco1.User" user "User.Eco1")
		(23 "Eco2.User" user "User.Eco2")
		(25 "Edge.Cuts" user "Board Geometry/Outline")
		(27 "Margin" user)
		(31 "F.CrtYd" user "Package Geometry/Place Bound Top")
		(29 "B.CrtYd" user "Package Geometry/Place Bound Bottom")
		(35 "F.Fab" user "Ref Des/Assembly Top")
		(33 "B.Fab" user "Ref Des/Assembly Bottom")
	)
	(footprint ""
		(layer "F.Cu")
		(at 40.36568 -258.091686)
		(property "Reference" "J19"
			(at -5.21716 -81.970372 0)
			(unlocked yes)
			(layer "F.SilkS")
			(effects
				(font
					(size 0.7874 0.5842)
					(thickness 0.1524)
				)
				(justify left)
			)
		)
		(property "Value" ""
			(at 0 0 0)
			(layer "F.Fab")
			(effects
				(font
					(size 1.27 1.27)
				)
			)
		)
		(duplicate_pad_numbers_are_jumpers no)
		(pad "183" smd rect
			(at 2.050034 -31.025084 270)
			(size 0.519938 1.4986)
			(layers "F.Cu" "F.Mask" "F.Paste")
			(net "M_B_CPU1_SA_DQ<23>")
		)
		(pad "184" smd rect
			(at 2.050034 -30.174946 270)
			(size 0.519938 1.4986)
			(layers "F.Cu" "F.Mask" "F.Paste")
			(net "GND")
		)
		(pad "185" smd rect
			(at 2.050034 -29.325062 270)
			(size 0.519938 1.4986)
			(layers "F.Cu" "F.Mask" "F.Paste")
			(net "M_B_CPU1_SA_DQ<26>")
		)
		(pad "186" smd rect
			(at 2.050034 -28.474924 270)
			(size 0.519938 1.4986)
			(layers "F.Cu" "F.Mask" "F.Paste")
			(net "GND")
		)
		(pad "187" smd rect
			(at 2.050034 -27.62504 270)
			(size 0.519938 1.4986)
			(layers "F.Cu" "F.Mask" "F.Paste")
			(net "M_B_CPU1_SA_DQ<27>")
		)
		(pad "188" smd rect
			(at 2.050034 -26.774902 270)
			(size 0.519938 1.4986)
			(layers "F.Cu" "F.Mask" "F.Paste")
			(net "GND")
		)
		(pad "189" smd rect
			(at 2.050034 -25.925018 270)
			(size 0.519938 1.4986)
			(layers "F.Cu" "F.Mask" "F.Paste")
			(net "M_B_CPU1_SA_DQS_DN<8>")
		)
		(pad "190" smd rect
			(at 2.050034 -25.07488 270)
			(size 0.519938 1.4986)
			(layers "F.Cu" "F.Mask" "F.Paste")
			(net "M_B_CPU1_SA_DQS_DP<8>")
		)
		(pad "191" smd rect
			(at 2.050034 -24.224996 270)
			(size 0.519938 1.4986)
			(layers "F.Cu" "F.Mask" "F.Paste")
			(net "GND")
		)
		(pad "192" smd rect
			(at 2.050034 -23.375112 270)
			(size 0.519938 1.4986)
			(layers "F.Cu" "F.Mask" "F.Paste")
			(net "M_B_CPU1_SA_DQ<30>")
		)
		(pad "193" smd rect
			(at 2.050034 -22.524974 270)
			(size 0.519938 1.4986)
			(layers "F.Cu" "F.Mask" "F.Paste")
			(net "GND")
		)
		(pad "194" smd rect
			(at 2.050034 -21.67509 270)
			(size 0.519938 1.4986)
			(layers "F.Cu" "F.Mask" "F.Paste")
			(net "M_B_CPU1_SA_DQ<31>")
		)
		(pad "195" smd rect
			(at 2.050034 -20.824952 270)
			(size 0.519938 1.4986)
			(layers "F.Cu" "F.Mask" "F.Paste")
			(net "GND")
		)
		(pad "196" smd rect
			(at 2.050034 -19.975068 270)
			(size 0.519938 1.4986)
			(layers "F.Cu" "F.Mask" "F.Paste")
			(net "M_B_CPU1_SA_CB<2>")
		)
		(pad "197" smd rect
			(at 2.050034 -19.12493 270)
			(size 0.519938 1.4986)
			(layers "F.Cu" "F.Mask" "F.Paste")
			(net "GND")
		)
		(pad "198" smd rect
			(at 2.050034 -18.275046 270)
			(size 0.519938 1.4986)
			(layers "F.Cu" "F.Mask" "F.Paste")
			(net "M_B_CPU1_SA_CB<3>")
		)
		(pad "199" smd rect
			(at 2.050034 -17.424908 270)
			(size 0.519938 1.4986)
			(layers "F.Cu" "F.Mask" "F.Paste")
			(net "GND")
		)
		(pad "200" smd rect
			(at 2.050034 -16.575024 270)
			(size 0.519938 1.4986)
			(layers "F.Cu" "F.Mask" "F.Paste")
			(net "M_B_CPU1_SA_DQS_DN<9>")
		)
		(pad "201" smd rect
			(at 2.050034 -15.724886 270)
			(size 0.519938 1.4986)
			(layers "F.Cu" "F.Mask" "F.Paste")
			(net "M_B_CPU1_SA_DQS_DP<9>")
		)
		(pad "202" smd rect
			(at 2.050034 -14.875002 270)
			(size 0.519938 1.4986)
			(layers "F.Cu" "F.Mask" "F.Paste")
			(net "GND")
		)
		(pad "203" smd rect
			(at 2.050034 -14.025118 270)
			(size 0.519938 1.4986)
			(layers "F.Cu" "F.Mask" "F.Paste")
			(net "M_B_CPU1_SA_CB<6>")
		)
		(pad "204" smd rect
			(at 2.050034 -13.17498 270)
			(size 0.519938 1.4986)
			(layers "F.Cu" "F.Mask" "F.Paste")
			(net "GND")
		)
		(pad "205" smd rect
			(at 2.050034 -12.325096 270)
			(size 0.519938 1.4986)
			(layers "F.Cu" "F.Mask" "F.Paste")
			(net "M_B_CPU1_SA_CB<7>")
		)
		(pad "206" smd rect
			(at 2.050034 -11.474958 270)
			(size 0.519938 1.4986)
			(layers "F.Cu" "F.Mask" "F.Paste")
			(net "GND")
		)
		(pad "207" smd rect
			(at 2.050034 -10.625074 270)
			(size 0.519938 1.4986)
			(layers "F.Cu" "F.Mask" "F.Paste")
			(net "RST_M_AB_CPU1_FPGA_N")
		)
		(pad "208" smd rect
			(at 2.050034 -9.774936 270)
			(size 0.519938 1.4986)
			(layers "F.Cu" "F.Mask" "F.Paste")
			(net "GND")
		)
		(pad "209" smd rect
			(at 2.050034 -8.925052 270)
			(size 0.519938 1.4986)
			(layers "F.Cu" "F.Mask" "F.Paste")
			(net "M_B_CPU1_SA_CS_N<1>")
		)
		(pad "210" smd rect
			(at 2.050034 -8.074914 270)
			(size 0.519938 1.4986)
			(layers "F.Cu" "F.Mask" "F.Paste")
			(net "GND")
		)
		(pad "211" smd rect
			(at 2.050034 -7.22503 270)
			(size 0.519938 1.4986)
			(layers "F.Cu" "F.Mask" "F.Paste")
			(net "M_B_CPU1_SA_CA<1>")
		)
		(pad "212" smd rect
			(at 2.050034 -6.374892 270)
			(size 0.519938 1.4986)
			(layers "F.Cu" "F.Mask" "F.Paste")
			(net "GND")
		)
		(pad "213" smd rect
			(at 2.050034 -5.525008 270)
			(size 0.519938 1.4986)
			(layers "F.Cu" "F.Mask" "F.Paste")
			(net "M_B_CPU1_SA_CA<3>")
		)
		(pad "214" smd rect
			(at 2.050034 -4.675124 270)
			(size 0.519938 1.4986)
			(layers "F.Cu" "F.Mask" "F.Paste")
			(net "GND")
		)
		(pad "215" smd rect
			(at 2.050034 -3.824986 270)
			(size 0.519938 1.4986)
			(layers "F.Cu" "F.Mask" "F.Paste")
			(net "M_B_CPU1_SA_CA<5>")
		)
		(pad "216" smd rect
			(at 2.050034 -2.975102 270)
			(size 0.519938 1.4986)
			(layers "F.Cu" "F.Mask" "F.Paste")
			(net "GND")
		)
		(pad "217" smd rect
			(at 2.050034 -2.124964 270)
			(size 0.519938 1.4986)
			(layers "F.Cu" "F.Mask" "F.Paste")
			(net "M_B_CPU1_CLK_DP<0>")
		)
		(pad "218" smd rect
			(at 2.050034 -1.27508 270)
			(size 0.519938 1.4986)
			(layers "F.Cu" "F.Mask" "F.Paste")
			(net "M_B_CPU1_CLK_DN<0>")
		)
		(pad "219" smd rect
			(at 2.050034 -0.424942 270)
			(size 0.519938 1.4986)
			(layers "F.Cu" "F.Mask" "F.Paste")
			(net "GND")
		)
		(pad "220" smd rect
			(at 2.050034 5.525008 270)
			(size 0.519938 1.4986)
			(layers "F.Cu" "F.Mask" "F.Paste")
			(net "TP_CHB_CPU1_DIMM1_FRU_4")
		)
		(pad "221" smd rect
			(at 2.050034 6.374892 270)
			(size 0.519938 1.4986)
			(layers "F.Cu" "F.Mask" "F.Paste")
			(net "M_B_CPU1_SB_CA<1>")
		)
		(pad "222" smd rect
			(at 2.050034 7.22503 270)
			(size 0.519938 1.4986)
			(layers "F.Cu" "F.Mask" "F.Paste")
			(net "GND")
		)
		(pad "223" smd rect
			(at 2.050034 8.074914 270)
			(size 0.519938 1.4986)
			(layers "F.Cu" "F.Mask" "F.Paste")
			(net "M_B_CPU1_SB_CA<3>")
		)
		(pad "224" smd rect
			(at 2.050034 8.925052 270)
			(size 0.519938 1.4986)
			(layers "F.Cu" "F.Mask" "F.Paste")
			(net "GND")
		)
		(pad "225" smd rect
			(at 2.050034 9.774936 270)
			(size 0.519938 1.4986)
			(layers "F.Cu" "F.Mask" "F.Paste")
			(net "M_B_CPU1_SB_CA<5>")
		)
		(pad "226" smd rect
			(at 2.050034 10.625074 270)
			(size 0.519938 1.4986)
			(layers "F.Cu" "F.Mask" "F.Paste")
			(net "GND")
		)
		(pad "227" smd rect
			(at 2.050034 11.474958 270)
			(size 0.519938 1.4986)
			(layers "F.Cu" "F.Mask" "F.Paste")
			(net "M_B_CPU1_SB_PAR")
		)
		(pad "228" smd rect
			(at 2.050034 12.325096 270)
			(size 0.519938 1.4986)
			(layers "F.Cu" "F.Mask" "F.Paste")
			(net "GND")
		)
	)
)
